(kicad_pcb
	(version 20241229)
	(generator "pcbnew")
	(generator_version "9.0")
	(general
		(thickness 1.599998)
		(legacy_teardrops no)
	)
	(paper "A4")
	(title_block
		(title "Artix - Datacenter Secure Control Module (DC-SCM)")
		(date "2024-11-06")
		(rev "1.1.3")
		(comment 9 "footprints 355-359 of 544")
	)
	(layers
		(0 "F.Cu" signal)
		(4 "In1.Cu" signal)
		(6 "In2.Cu" signal)
		(8 "In3.Cu" signal)
		(10 "In4.Cu" signal)
		(12 "In5.Cu" signal)
		(14 "In6.Cu" signal)
		(2 "B.Cu" signal)
		(9 "F.Adhes" user "F.Adhesive")
		(11 "B.Adhes" user "B.Adhesive")
		(13 "F.Paste" user)
		(15 "B.Paste" user)
		(5 "F.SilkS" user "F.Silkscreen")
		(7 "B.SilkS" user "B.Silkscreen")
		(1 "F.Mask" user)
		(3 "B.Mask" user)
		(17 "Dwgs.User" user "User.Drawings")
		(19 "Cmts.User" user "User.Comments")
		(21 "Eco1.User" user "User.Eco1")
		(23 "Eco2.User" user "User.Eco2")
		(25 "Edge.Cuts" user)
		(27 "Margin" user)
		(31 "F.CrtYd" user "F.Courtyard")
		(29 "B.CrtYd" user "B.Courtyard")
		(35 "F.Fab" user)
		(33 "B.Fab" user)
	)
	(footprint "antmicro-footprints:C_0402_1005Metric"
		(layer "B.Cu")
		(at 104.8 98.12 -90)
		(descr "Capacitor SMD 0402")
		(tags "capacitor SMD 0402")
		(property "Reference" "C212"
			(at -3.62 -0.36 90)
			(layer "B.SilkS")
			(effects
				(font
					(size 0.7 0.7)
					(thickness 0.15)
				)
				(justify left bottom mirror)
			)
		)
		(property "Value" "C_10n_0402"
			(at 0 -1.4 90)
			(layer "B.Fab")
			(effects
				(font
					(size 0.7 0.7)
					(thickness 0.15)
				)
				(justify left bottom mirror)
			)
		)
		(property "Datasheet" "https://www.murata.com/products/productdetail?partno=GRM155R71H103KA88%23"
			(at 0 0 270)
			(layer "F.Fab")
			(hide yes)
			(effects
				(font
					(size 1.27 1.27)
					(thickness 0.15)
				)
			)
		)
		(property "Description" "SMD Multilayer Ceramic Capacitor, 10000 pF, 50 V, 0402 [1005 Metric], ± 10%, X7R, GRM Series"
			(at 0 0 270)
			(layer "F.Fab")
			(hide yes)
			(effects
				(font
					(size 1.27 1.27)
					(thickness 0.15)
				)
			)
		)
		(property "Author" "Antmicro"
			(at 6.68 202.92 0)
			(layer "B.Fab")
			(hide yes)
			(effects
				(font
					(size 1 1)
					(thickness 0.15)
				)
				(justify mirror)
			)
		)
		(property "Dielectric" "X7R"
			(at 6.68 202.92 0)
			(layer "B.Fab")
			(hide yes)
			(effects
				(font
					(size 1 1)
					(thickness 0.15)
				)
				(justify mirror)
			)
		)
		(property "License" "Apache-2.0"
			(at 6.68 202.92 0)
			(layer "B.Fab")
			(hide yes)
			(effects
				(font
					(size 1 1)
					(thickness 0.15)
				)
				(justify mirror)
			)
		)
		(property "MPN" "GRM155R71H103KA88D"
			(at 6.68 202.92 0)
			(layer "B.Fab")
			(hide yes)
			(effects
				(font
					(size 1 1)
					(thickness 0.15)
				)
				(justify mirror)
			)
		)
		(property "Manufacturer" "Murata"
			(at 6.68 202.92 0)
			(layer "B.Fab")
			(hide yes)
			(effects
				(font
					(size 1 1)
					(thickness 0.15)
				)
				(justify mirror)
			)
		)
		(property "Val" "10n"
			(at 6.68 202.92 0)
			(layer "B.Fab")
			(hide yes)
			(effects
				(font
					(size 1 1)
					(thickness 0.15)
				)
				(justify mirror)
			)
		)
		(property "Voltage" "50V"
			(at 6.68 202.92 0)
			(layer "B.Fab")
			(hide yes)
			(effects
				(font
					(size 1 1)
					(thickness 0.15)
				)
				(justify mirror)
			)
		)
		(sheetname "/Ethernet/")
		(sheetfile "ethernet.kicad_sch")
		(attr smd)
		(fp_rect
			(start -0.925 0.47)
			(end 0.925 -0.47)
			(stroke
				(width 0.05)
				(type default)
			)
			(fill no)
			(layer "B.CrtYd")
		)
		(fp_line
			(start -0.494 0.25)
			(end 0.504 0.25)
			(stroke
				(width 0.15)
				(type solid)
			)
			(layer "B.Fab")
		)
		(fp_line
			(start 0.504 0.25)
			(end 0.504 -0.248)
			(stroke
				(width 0.15)
				(type solid)
			)
			(layer "B.Fab")
		)
		(fp_line
			(start -0.494 -0.248)
			(end -0.494 0.25)
			(stroke
				(width 0.15)
				(type solid)
			)
			(layer "B.Fab")
		)
		(fp_line
			(start 0.504 -0.248)
			(end -0.494 -0.248)
			(stroke
				(width 0.15)
				(type solid)
			)
			(layer "B.Fab")
		)
		(pad "1" smd roundrect
			(at -0.48 0 270)
			(size 0.59 0.64)
			(layers "B.Cu" "B.Mask" "B.Paste")
			(roundrect_rratio 0.25)
			(net 1 "GND")
			(pintype "passive")
		)
		(pad "2" smd roundrect
			(at 0.48 0 270)
			(size 0.59 0.64)
			(layers "B.Cu" "B.Mask" "B.Paste")
			(roundrect_rratio 0.25)
			(net 2 "VCC3V3")
			(pintype "passive")
		)
	)
	(footprint "antmicro-footprints:C_0402_1005Metric"
		(layer "B.Cu")
		(at 101.8 90.765 -90)
		(descr "Capacitor SMD 0402")
		(tags "capacitor SMD 0402")
		(property "Reference" "C213"
			(at -3.649 -0.4 90)
			(layer "B.SilkS")
			(effects
				(font
					(size 0.7 0.7)
					(thickness 0.15)
				)
				(justify left bottom mirror)
			)
		)
		(property "Value" "C_10n_0402"
			(at 0 -1.4 90)
			(layer "B.Fab")
			(effects
				(font
					(size 0.7 0.7)
					(thickness 0.15)
				)
				(justify left bottom mirror)
			)
		)
		(property "Datasheet" "https://www.murata.com/products/productdetail?partno=GRM155R71H103KA88%23"
			(at 0 0 270)
			(layer "F.Fab")
			(hide yes)
			(effects
				(font
					(size 1.27 1.27)
					(thickness 0.15)
				)
			)
		)
		(property "Description" "SMD Multilayer Ceramic Capacitor, 10000 pF, 50 V, 0402 [1005 Metric], ± 10%, X7R, GRM Series"
			(at 0 0 270)
			(layer "F.Fab")
			(hide yes)
			(effects
				(font
					(size 1.27 1.27)
					(thickness 0.15)
				)
			)
		)
		(property "Author" "Antmicro"
			(at 11.035 192.565 0)
			(layer "B.Fab")
			(hide yes)
			(effects
				(font
					(size 1 1)
					(thickness 0.15)
				)
				(justify mirror)
			)
		)
		(property "Dielectric" "X7R"
			(at 11.035 192.565 0)
			(layer "B.Fab")
			(hide yes)
			(effects
				(font
					(size 1 1)
					(thickness 0.15)
				)
				(justify mirror)
			)
		)
		(property "License" "Apache-2.0"
			(at 11.035 192.565 0)
			(layer "B.Fab")
			(hide yes)
			(effects
				(font
					(size 1 1)
					(thickness 0.15)
				)
				(justify mirror)
			)
		)
		(property "MPN" "GRM155R71H103KA88D"
			(at 11.035 192.565 0)
			(layer "B.Fab")
			(hide yes)
			(effects
				(font
					(size 1 1)
					(thickness 0.15)
				)
				(justify mirror)
			)
		)
		(property "Manufacturer" "Murata"
			(at 11.035 192.565 0)
			(layer "B.Fab")
			(hide yes)
			(effects
				(font
					(size 1 1)
					(thickness 0.15)
				)
				(justify mirror)
			)
		)
		(property "Val" "10n"
			(at 11.035 192.565 0)
			(layer "B.Fab")
			(hide yes)
			(effects
				(font
					(size 1 1)
					(thickness 0.15)
				)
				(justify mirror)
			)
		)
		(property "Voltage" "50V"
			(at 11.035 192.565 0)
			(layer "B.Fab")
			(hide yes)
			(effects
				(font
					(size 1 1)
					(thickness 0.15)
				)
				(justify mirror)
			)
		)
		(sheetname "/Ethernet/")
		(sheetfile "ethernet.kicad_sch")
		(attr smd)
		(fp_rect
			(start -0.925 0.47)
			(end 0.925 -0.47)
			(stroke
				(width 0.05)
				(type default)
			)
			(fill no)
			(layer "B.CrtYd")
		)
		(fp_line
			(start -0.494 0.25)
			(end 0.504 0.25)
			(stroke
				(width 0.15)
				(type solid)
			)
			(layer "B.Fab")
		)
		(fp_line
			(start 0.504 0.25)
			(end 0.504 -0.248)
			(stroke
				(width 0.15)
				(type solid)
			)
			(layer "B.Fab")
		)
		(fp_line
			(start -0.494 -0.248)
			(end -0.494 0.25)
			(stroke
				(width 0.15)
				(type solid)
			)
			(layer "B.Fab")
		)
		(fp_line
			(start 0.504 -0.248)
			(end -0.494 -0.248)
			(stroke
				(width 0.15)
				(type solid)
			)
			(layer "B.Fab")
		)
		(pad "1" smd roundrect
			(at -0.48 0 270)
			(size 0.59 0.64)
			(layers "B.Cu" "B.Mask" "B.Paste")
			(roundrect_rratio 0.25)
			(net 1 "GND")
			(pintype "passive")
		)
		(pad "2" smd roundrect
			(at 0.48 0 270)
			(size 0.59 0.64)
			(layers "B.Cu" "B.Mask" "B.Paste")
			(roundrect_rratio 0.25)
			(net 405 "/Ethernet/AVDDL")
			(pintype "passive")
		)
	)
	(footprint "antmicro-footprints:C_0402_1005Metric"
		(layer "B.Cu")
		(at 102.6 98.1 -90)
		(descr "Capacitor SMD 0402")
		(tags "capacitor SMD 0402")
		(property "Reference" "C217"
			(at -3.62 -0.36 90)
			(layer "B.SilkS")
			(effects
				(font
					(size 0.7 0.7)
					(thickness 0.15)
				)
				(justify left bottom mirror)
			)
		)
		(property "Value" "C_10n_0402"
			(at 0 -1.4 90)
			(layer "B.Fab")
			(effects
				(font
					(size 0.7 0.7)
					(thickness 0.15)
				)
				(justify left bottom mirror)
			)
		)
		(property "Datasheet" "https://www.murata.com/products/productdetail?partno=GRM155R71H103KA88%23"
			(at 0 0 270)
			(layer "F.Fab")
			(hide yes)
			(effects
				(font
					(size 1.27 1.27)
					(thickness 0.15)
				)
			)
		)
		(property "Description" "SMD Multilayer Ceramic Capacitor, 10000 pF, 50 V, 0402 [1005 Metric], ± 10%, X7R, GRM Series"
			(at 0 0 270)
			(layer "F.Fab")
			(hide yes)
			(effects
				(font
					(size 1.27 1.27)
					(thickness 0.15)
				)
			)
		)
		(property "Author" "Antmicro"
			(at 4.5 200.7 0)
			(layer "B.Fab")
			(hide yes)
			(effects
				(font
					(size 1 1)
					(thickness 0.15)
				)
				(justify mirror)
			)
		)
		(property "Dielectric" "X7R"
			(at 4.5 200.7 0)
			(layer "B.Fab")
			(hide yes)
			(effects
				(font
					(size 1 1)
					(thickness 0.15)
				)
				(justify mirror)
			)
		)
		(property "License" "Apache-2.0"
			(at 4.5 200.7 0)
			(layer "B.Fab")
			(hide yes)
			(effects
				(font
					(size 1 1)
					(thickness 0.15)
				)
				(justify mirror)
			)
		)
		(property "MPN" "GRM155R71H103KA88D"
			(at 4.5 200.7 0)
			(layer "B.Fab")
			(hide yes)
			(effects
				(font
					(size 1 1)
					(thickness 0.15)
				)
				(justify mirror)
			)
		)
		(property "Manufacturer" "Murata"
			(at 4.5 200.7 0)
			(layer "B.Fab")
			(hide yes)
			(effects
				(font
					(size 1 1)
					(thickness 0.15)
				)
				(justify mirror)
			)
		)
		(property "Val" "10n"
			(at 4.5 200.7 0)
			(layer "B.Fab")
			(hide yes)
			(effects
				(font
					(size 1 1)
					(thickness 0.15)
				)
				(justify mirror)
			)
		)
		(property "Voltage" "50V"
			(at 4.5 200.7 0)
			(layer "B.Fab")
			(hide yes)
			(effects
				(font
					(size 1 1)
					(thickness 0.15)
				)
				(justify mirror)
			)
		)
		(sheetname "/Ethernet/")
		(sheetfile "ethernet.kicad_sch")
		(attr smd)
		(fp_rect
			(start -0.925 0.47)
			(end 0.925 -0.47)
			(stroke
				(width 0.05)
				(type default)
			)
			(fill no)
			(layer "B.CrtYd")
		)
		(fp_line
			(start -0.494 0.25)
			(end 0.504 0.25)
			(stroke
				(width 0.15)
				(type solid)
			)
			(layer "B.Fab")
		)
		(fp_line
			(start 0.504 0.25)
			(end 0.504 -0.248)
			(stroke
				(width 0.15)
				(type solid)
			)
			(layer "B.Fab")
		)
		(fp_line
			(start -0.494 -0.248)
			(end -0.494 0.25)
			(stroke
				(width 0.15)
				(type solid)
			)
			(layer "B.Fab")
		)
		(fp_line
			(start 0.504 -0.248)
			(end -0.494 -0.248)
			(stroke
				(width 0.15)
				(type solid)
			)
			(layer "B.Fab")
		)
		(pad "1" smd roundrect
			(at -0.48 0 270)
			(size 0.59 0.64)
			(layers "B.Cu" "B.Mask" "B.Paste")
			(roundrect_rratio 0.25)
			(net 1 "GND")
			(pintype "passive")
		)
		(pad "2" smd roundrect
			(at 0.48 0 270)
			(size 0.59 0.64)
			(layers "B.Cu" "B.Mask" "B.Paste")
			(roundrect_rratio 0.25)
			(net 339 "VCC1V2")
			(pintype "passive")
		)
	)
	(footprint "antmicro-footprints:FB_0603_1608Metric"
		(layer "B.Cu")
		(at 104.9 90.45 -90)
		(property "Reference" "FB4"
			(at -3.35 -0.3 90)
			(layer "B.SilkS")
			(effects
				(font
					(size 0.7 0.7)
					(thickness 0.15)
				)
				(justify left bottom mirror)
			)
		)
		(property "Value" "FB_120Z_2A_Murata-BLM18PG_0603"
			(at 0 -1.7 90)
			(layer "B.Fab")
			(effects
				(font
					(size 0.7 0.7)
					(thickness 0.15)
				)
				(justify left bottom mirror)
			)
		)
		(property "Datasheet" "https://www.murata.com/en-us/products/productdata/8796738650142/ENFA0003.pdf"
			(at 0 0 270)
			(layer "F.Fab")
			(hide yes)
			(effects
				(font
					(size 1.27 1.27)
					(thickness 0.15)
				)
			)
		)
		(property "Description" "Ferrite Bead, 0603 [1608 Metric], 120 ohm, 2 A, BLM18P, 0.05 ohm, ± 25%, DC power line"
			(at 0 0 270)
			(layer "F.Fab")
			(hide yes)
			(effects
				(font
					(size 1.27 1.27)
					(thickness 0.15)
				)
			)
		)
		(property "Author" "Antmicro"
			(at 14.45 195.35 0)
			(layer "B.Fab")
			(hide yes)
			(effects
				(font
					(size 1 1)
					(thickness 0.15)
				)
				(justify mirror)
			)
		)
		(property "Current" ""
			(at 14.45 195.35 0)
			(layer "B.Fab")
			(hide yes)
			(effects
				(font
					(size 1 1)
					(thickness 0.15)
				)
				(justify mirror)
			)
		)
		(property "License" "Apache-2.0"
			(at 14.45 195.35 0)
			(layer "B.Fab")
			(hide yes)
			(effects
				(font
					(size 1 1)
					(thickness 0.15)
				)
				(justify mirror)
			)
		)
		(property "MPN" "BLM18PG121SN1D"
			(at 14.45 195.35 0)
			(layer "B.Fab")
			(hide yes)
			(effects
				(font
					(size 1 1)
					(thickness 0.15)
				)
				(justify mirror)
			)
		)
		(property "Manufacturer" "Murata"
			(at 14.45 195.35 0)
			(layer "B.Fab")
			(hide yes)
			(effects
				(font
					(size 1 1)
					(thickness 0.15)
				)
				(justify mirror)
			)
		)
		(property "Val" "120Z/2A"
			(at 14.45 195.35 0)
			(layer "B.Fab")
			(hide yes)
			(effects
				(font
					(size 1 1)
					(thickness 0.15)
				)
				(justify mirror)
			)
		)
		(sheetname "/Ethernet/")
		(sheetfile "ethernet.kicad_sch")
		(attr smd)
		(fp_line
			(start -0.15 0.4)
			(end 0.15 0.4)
			(stroke
				(width 0.15)
				(type solid)
			)
			(layer "B.SilkS")
		)
		(fp_line
			(start -0.15 -0.4)
			(end 0.15 -0.4)
			(stroke
				(width 0.15)
				(type solid)
			)
			(layer "B.SilkS")
		)
		(fp_rect
			(start -1.25 0.65)
			(end 1.25 -0.65)
			(stroke
				(width 0.05)
				(type solid)
			)
			(fill no)
			(layer "B.CrtYd")
		)
		(fp_line
			(start 0.8 0.408)
			(end -0.803 0.408)
			(stroke
				(width 0.15)
				(type solid)
			)
			(layer "B.Fab")
		)
		(fp_line
			(start 0.8 0.408)
			(end 0.8 -0.406)
			(stroke
				(width 0.15)
				(type solid)
			)
			(layer "B.Fab")
		)
		(fp_line
			(start -0.803 -0.406)
			(end -0.803 0.408)
			(stroke
				(width 0.15)
				(type solid)
			)
			(layer "B.Fab")
		)
		(fp_line
			(start 0.8 -0.406)
			(end -0.803 -0.406)
			(stroke
				(width 0.15)
				(type solid)
			)
			(layer "B.Fab")
		)
		(pad "1" smd roundrect
			(at -0.7 0 270)
			(size 0.8 1)
			(layers "B.Cu" "B.Mask" "B.Paste")
			(roundrect_rratio 0.2)
			(net 2 "VCC3V3")
			(pintype "passive")
		)
		(pad "2" smd roundrect
			(at 0.7 0 270)
			(size 0.8 1)
			(layers "B.Cu" "B.Mask" "B.Paste")
			(roundrect_rratio 0.2)
			(net 406 "/Ethernet/AVDDH")
			(pintype "passive")
		)
	)
	(footprint "antmicro-footprints:FB_0603_1608Metric"
		(layer "B.Cu")
		(at 99.66 90.47 90)
		(property "Reference" "FB6"
			(at 1.27 0.44 90)
			(layer "B.SilkS")
			(effects
				(font
					(size 0.7 0.7)
					(thickness 0.15)
				)
				(justify right bottom mirror)
			)
		)
		(property "Value" "FB_120Z_2A_Murata-BLM18PG_0603"
			(at 0 -1.7 90)
			(layer "B.Fab")
			(effects
				(font
					(size 0.7 0.7)
					(thickness 0.15)
				)
				(justify right bottom mirror)
			)
		)
		(property "Datasheet" "https://www.murata.com/en-us/products/productdata/8796738650142/ENFA0003.pdf"
			(at 0 0 90)
			(layer "F.Fab")
			(hide yes)
			(effects
				(font
					(size 1.27 1.27)
					(thickness 0.15)
				)
			)
		)
		(property "Description" "Ferrite Bead, 0603 [1608 Metric], 120 ohm, 2 A, BLM18P, 0.05 ohm, ± 25%, DC power line"
			(at 0 0 90)
			(layer "F.Fab")
			(hide yes)
			(effects
				(font
					(size 1.27 1.27)
					(thickness 0.15)
				)
			)
		)
		(property "Author" "Antmicro"
			(at 190.13 -9.19 0)
			(layer "B.Fab")
			(hide yes)
			(effects
				(font
					(size 1 1)
					(thickness 0.15)
				)
				(justify mirror)
			)
		)
		(property "Current" ""
			(at 190.13 -9.19 0)
			(layer "B.Fab")
			(hide yes)
			(effects
				(font
					(size 1 1)
					(thickness 0.15)
				)
				(justify mirror)
			)
		)
		(property "License" "Apache-2.0"
			(at 190.13 -9.19 0)
			(layer "B.Fab")
			(hide yes)
			(effects
				(font
					(size 1 1)
					(thickness 0.15)
				)
				(justify mirror)
			)
		)
		(property "MPN" "BLM18PG121SN1D"
			(at 190.13 -9.19 0)
			(layer "B.Fab")
			(hide yes)
			(effects
				(font
					(size 1 1)
					(thickness 0.15)
				)
				(justify mirror)
			)
		)
		(property "Manufacturer" "Murata"
			(at 190.13 -9.19 0)
			(layer "B.Fab")
			(hide yes)
			(effects
				(font
					(size 1 1)
					(thickness 0.15)
				)
				(justify mirror)
			)
		)
		(property "Val" "120Z/2A"
			(at 190.13 -9.19 0)
			(layer "B.Fab")
			(hide yes)
			(effects
				(font
					(size 1 1)
					(thickness 0.15)
				)
				(justify mirror)
			)
		)
		(sheetname "/Ethernet/")
		(sheetfile "ethernet.kicad_sch")
		(attr smd)
		(fp_line
			(start -0.15 -0.4)
			(end 0.15 -0.4)
			(stroke
				(width 0.15)
				(type solid)
			)
			(layer "B.SilkS")
		)
		(fp_line
			(start -0.15 0.4)
			(end 0.15 0.4)
			(stroke
				(width 0.15)
				(type solid)
			)
			(layer "B.SilkS")
		)
		(fp_rect
			(start -1.25 0.65)
			(end 1.25 -0.65)
			(stroke
				(width 0.05)
				(type solid)
			)
			(fill no)
			(layer "B.CrtYd")
		)
		(fp_line
			(start 0.8 -0.406)
			(end -0.803 -0.406)
			(stroke
				(width 0.15)
				(type solid)
			)
			(layer "B.Fab")
		)
		(fp_line
			(start -0.803 -0.406)
			(end -0.803 0.408)
			(stroke
				(width 0.15)
				(type solid)
			)
			(layer "B.Fab")
		)
		(fp_line
			(start 0.8 0.408)
			(end 0.8 -0.406)
			(stroke
				(width 0.15)
				(type solid)
			)
			(layer "B.Fab")
		)
		(fp_line
			(start 0.8 0.408)
			(end -0.803 0.408)
			(stroke
				(width 0.15)
				(type solid)
			)
			(layer "B.Fab")
		)
		(pad "1" smd roundrect
			(at -0.7 0 90)
			(size 0.8 1)
			(layers "B.Cu" "B.Mask" "B.Paste")
			(roundrect_rratio 0.2)
			(net 405 "/Ethernet/AVDDL")
			(pintype "passive")
		)
		(pad "2" smd roundrect
			(at 0.7 0 90)
			(size 0.8 1)
			(layers "B.Cu" "B.Mask" "B.Paste")
			(roundrect_rratio 0.2)
			(net 339 "VCC1V2")
			(pintype "passive")
		)
	)
)
